(kicad_pcb
	(version 20260206)
	(generator "pcbnew")
	(generator_version "10.0")
	(general
		(thickness 1.6)
		(legacy_teardrops no)
	)
	(paper "A4")
	(title_block
		(title "01162023_DA0F0TEBIF0_F0T_Expander_BD_F_brd_V02_OCP.brd")
		(comment 1 "Grand Teton / footprints 4793-4797 of 9728")
	)
	(layers
		(0 "F.Cu" signal "TOP")
		(4 "In1.Cu" signal "GND")
		(6 "In2.Cu" signal "VCC")
		(8 "In3.Cu" signal "VCC1")
		(10 "In4.Cu" signal "GND1")
		(12 "In5.Cu" signal "IN1")
		(14 "In6.Cu" signal "GND2")
		(16 "In7.Cu" signal "IN2")
		(18 "In8.Cu" signal "GND3")
		(20 "In9.Cu" signal "IN3")
		(22 "In10.Cu" signal "GND4")
		(24 "In11.Cu" signal "IN4")
		(26 "In12.Cu" signal "GND5")
		(28 "In13.Cu" signal "IN5")
		(30 "In14.Cu" signal "GND6")
		(32 "In15.Cu" signal "IN6")
		(34 "In16.Cu" signal "GND7")
		(2 "B.Cu" signal "BOTTOM")
		(9 "F.Adhes" user "F.Adhesive")
		(11 "B.Adhes" user "B.Adhesive")
		(13 "F.Paste" user "Package Geometry/Pastemask Top")
		(15 "B.Paste" user "Package Geometry/Pastemask Bottom")
		(5 "F.SilkS" user "Ref Des/Silkscreen Top")
		(7 "B.SilkS" user "Ref Des/Silkscreen Bottom")
		(1 "F.Mask" user "Board Geometry/Soldermask Top")
		(3 "B.Mask" user "Board Geometry/Soldermask Bottom")
		(17 "Dwgs.User" user "User.Drawings")
		(19 "Cmts.User" user "User.Comments")
		(21 "Eco1.User" user "User.Eco1")
		(23 "Eco2.User" user "User.Eco2")
		(25 "Edge.Cuts" user "Board Geometry/Outline")
		(27 "Margin" user)
		(31 "F.CrtYd" user "Package Geometry/Place Bound Top")
		(29 "B.CrtYd" user "Package Geometry/Place Bound Bottom")
		(35 "F.Fab" user "Ref Des/Assembly Top")
		(33 "B.Fab" user "Ref Des/Assembly Bottom")
	)
	(footprint ""
		(layer "F.Cu")
		(at 369.24742 -21.37156)
		(property "Reference" "C3961"
			(at 0 0 0)
			(layer "F.SilkS")
			(hide yes)
			(effects
				(font
					(size 1.27 1.27)
				)
			)
		)
		(property "Value" ""
			(at 0 0 0)
			(layer "F.Fab")
			(effects
				(font
					(size 1.27 1.27)
				)
			)
		)
		(duplicate_pad_numbers_are_jumpers no)
		(fp_line
			(start -0.7874 -0.4064)
			(end 0.7874 -0.4064)
			(stroke
				(width 0.1524)
				(type default)
			)
			(layer "F.SilkS")
		)
		(fp_line
			(start -0.7874 0.4064)
			(end -0.7874 -0.4064)
			(stroke
				(width 0.1524)
				(type default)
			)
			(layer "F.SilkS")
		)
		(fp_line
			(start 0.7874 -0.4064)
			(end 0.7874 0.4064)
			(stroke
				(width 0.1524)
				(type default)
			)
			(layer "F.SilkS")
		)
		(fp_line
			(start 0.7874 0.4064)
			(end -0.7874 0.4064)
			(stroke
				(width 0.1524)
				(type default)
			)
			(layer "F.SilkS")
		)
		(fp_line
			(start -0.67945 -0.305054)
			(end -0.12065 -0.305054)
			(stroke
				(width 0.1)
				(type default)
			)
			(layer "F.Fab")
		)
		(fp_line
			(start -0.67945 0.3048)
			(end -0.67945 -0.305054)
			(stroke
				(width 0.1)
				(type default)
			)
			(layer "F.Fab")
		)
		(fp_line
			(start -0.12065 -0.305054)
			(end -0.12065 -0.2794)
			(stroke
				(width 0.1)
				(type default)
			)
			(layer "F.Fab")
		)
		(fp_line
			(start -0.12065 -0.2794)
			(end 0.12065 -0.2794)
			(stroke
				(width 0.1)
				(type default)
			)
			(layer "F.Fab")
		)
		(fp_line
			(start -0.12065 0.2794)
			(end -0.12065 0.3048)
			(stroke
				(width 0.1)
				(type default)
			)
			(layer "F.Fab")
		)
		(fp_line
			(start -0.12065 0.3048)
			(end -0.67945 0.3048)
			(stroke
				(width 0.1)
				(type default)
			)
			(layer "F.Fab")
		)
		(fp_line
			(start 0.120396 0.2794)
			(end -0.12065 0.2794)
			(stroke
				(width 0.1)
				(type default)
			)
			(layer "F.Fab")
		)
		(fp_line
			(start 0.120396 0.3048)
			(end 0.120396 0.2794)
			(stroke
				(width 0.1)
				(type default)
			)
			(layer "F.Fab")
		)
		(fp_line
			(start 0.12065 -0.3048)
			(end 0.67945 -0.3048)
			(stroke
				(width 0.1)
				(type default)
			)
			(layer "F.Fab")
		)
		(fp_line
			(start 0.12065 -0.2794)
			(end 0.12065 -0.3048)
			(stroke
				(width 0.1)
				(type default)
			)
			(layer "F.Fab")
		)
		(fp_line
			(start 0.67945 -0.3048)
			(end 0.67945 0.3048)
			(stroke
				(width 0.1)
				(type default)
			)
			(layer "F.Fab")
		)
		(fp_line
			(start 0.67945 0.3048)
			(end 0.120396 0.3048)
			(stroke
				(width 0.1)
				(type default)
			)
			(layer "F.Fab")
		)
		(pad "1" smd circle
			(at -0.40005 0)
			(size 0 0)
			(layers "F.Cu" "F.Mask" "F.Paste")
			(net "P12V_SSD12")
		)
		(pad "2" smd circle
			(at 0.40005 0)
			(size 0 0)
			(layers "F.Cu" "F.Mask" "F.Paste")
			(net "GND")
		)
	)
	(footprint ""
		(layer "F.Cu")
		(at 210.595972 -216.907364 -90)
		(property "Reference" "U89"
			(at 3.997706 0.131318 90)
			(unlocked yes)
			(layer "F.SilkS")
			(effects
				(font
					(size 0.7874 0.5842)
					(thickness 0.1524)
				)
				(justify left)
			)
		)
		(property "Value" ""
			(at 0 0 270)
			(layer "F.Fab")
			(effects
				(font
					(size 1.27 1.27)
				)
			)
		)
		(duplicate_pad_numbers_are_jumpers no)
		(fp_line
			(start -0.8636 1.050036)
			(end 0.8636 1.050036)
			(stroke
				(width 0.1524)
				(type default)
			)
			(layer "F.SilkS")
		)
		(fp_line
			(start 0.8636 1.050036)
			(end 0.8636 -1.050036)
			(stroke
				(width 0.1524)
				(type default)
			)
			(layer "F.SilkS")
		)
		(fp_line
			(start 0 -0.508)
			(end -0.542036 -1.050036)
			(stroke
				(width 0.1524)
				(type default)
			)
			(layer "F.SilkS")
		)
		(fp_line
			(start -0.8636 -1.050036)
			(end -0.8636 1.050036)
			(stroke
				(width 0.1524)
				(type default)
			)
			(layer "F.SilkS")
		)
		(fp_line
			(start -0.542036 -1.050036)
			(end -0.8636 -1.050036)
			(stroke
				(width 0.1524)
				(type default)
			)
			(layer "F.SilkS")
		)
		(fp_line
			(start 0.542036 -1.050036)
			(end 0 -0.508)
			(stroke
				(width 0.1524)
				(type default)
			)
			(layer "F.SilkS")
		)
		(fp_line
			(start 0.8636 -1.050036)
			(end 0.542036 -1.050036)
			(stroke
				(width 0.1524)
				(type default)
			)
			(layer "F.SilkS")
		)
		(fp_poly
			(pts
				(xy -2.794 -1.258062) (xy -2.794 -0.242062) (xy -1.778 -0.750062)
			)
			(stroke
				(width 0)
				(type default)
			)
			(fill yes)
			(layer "F.SilkS")
		)
		(fp_line
			(start -1.199896 1.050036)
			(end 1.199896 1.050036)
			(stroke
				(width 0.1)
				(type default)
			)
			(layer "F.Fab")
		)
		(fp_line
			(start 1.199896 1.050036)
			(end 1.199896 -1.050036)
			(stroke
				(width 0.1)
				(type default)
			)
			(layer "F.Fab")
		)
		(fp_line
			(start -1.199896 -1.050036)
			(end -1.199896 1.050036)
			(stroke
				(width 0.1)
				(type default)
			)
			(layer "F.Fab")
		)
		(fp_line
			(start 1.199896 -1.050036)
			(end -1.199896 -1.050036)
			(stroke
				(width 0.1)
				(type default)
			)
			(layer "F.Fab")
		)
		(fp_poly
			(pts
				(xy -2.794 -1.258062) (xy -2.794 -0.242062) (xy -1.778 -0.750062)
			)
			(stroke
				(width 0)
				(type default)
			)
			(fill yes)
			(layer "F.Fab")
		)
		(pad "1" smd rect
			(at -1.35001 -0.750062 180)
			(size 0.2794 0.7112)
			(layers "F.Cu" "F.Mask" "F.Paste")
			(net "TP_FSA3357K8X_B2_TX")
		)
		(pad "2" smd rect
			(at -1.35001 -0.249936 180)
			(size 0.2794 0.7112)
			(layers "F.Cu" "F.Mask" "F.Paste")
			(net "UART_MB_BIC_TX")
		)
		(pad "3" smd rect
			(at -1.35001 0.249936 180)
			(size 0.2794 0.7112)
			(layers "F.Cu" "F.Mask" "F.Paste")
			(net "UART_FIO_DEBUG_R_TX")
		)
		(pad "4" smd rect
			(at -1.35001 0.750062 180)
			(size 0.2794 0.7112)
			(layers "F.Cu" "F.Mask" "F.Paste")
			(net "GND")
		)
		(pad "5" smd rect
			(at 1.35001 0.750062 180)
			(size 0.2794 0.7112)
			(layers "F.Cu" "F.Mask" "F.Paste")
			(net "BIC_UART_SEL2")
		)
		(pad "6" smd rect
			(at 1.35001 0.249936 180)
			(size 0.2794 0.7112)
			(layers "F.Cu" "F.Mask" "F.Paste")
			(net "BIC_UART_SEL1")
		)
		(pad "7" smd rect
			(at 1.35001 -0.249936 180)
			(size 0.2794 0.7112)
			(layers "F.Cu" "F.Mask" "F.Paste")
			(net "UART_BIC_DEBUG_R_TX")
		)
		(pad "8" smd rect
			(at 1.35001 -0.750062 180)
			(size 0.2794 0.7112)
			(layers "F.Cu" "F.Mask" "F.Paste")
			(net "P3V3_AUX")
		)
	)
	(footprint ""
		(layer "F.Cu")
		(at 81.872074 -32.848042 90)
		(property "Reference" "PC682"
			(at 0 0 90)
			(layer "F.SilkS")
			(hide yes)
			(effects
				(font
					(size 1.27 1.27)
				)
			)
		)
		(property "Value" ""
			(at 0 0 90)
			(layer "F.Fab")
			(effects
				(font
					(size 1.27 1.27)
				)
			)
		)
		(duplicate_pad_numbers_are_jumpers no)
		(fp_line
			(start 0.7874 -0.4064)
			(end 0.7874 0.4064)
			(stroke
				(width 0.1524)
				(type default)
			)
			(layer "F.SilkS")
		)
		(fp_line
			(start -0.7874 -0.4064)
			(end 0.7874 -0.4064)
			(stroke
				(width 0.1524)
				(type default)
			)
			(layer "F.SilkS")
		)
		(fp_line
			(start 0.7874 0.4064)
			(end -0.7874 0.4064)
			(stroke
				(width 0.1524)
				(type default)
			)
			(layer "F.SilkS")
		)
		(fp_line
			(start -0.7874 0.4064)
			(end -0.7874 -0.4064)
			(stroke
				(width 0.1524)
				(type default)
			)
			(layer "F.SilkS")
		)
		(fp_line
			(start -0.12065 -0.305054)
			(end -0.12065 -0.2794)
			(stroke
				(width 0.1)
				(type default)
			)
			(layer "F.Fab")
		)
		(fp_line
			(start -0.67945 -0.305054)
			(end -0.12065 -0.305054)
			(stroke
				(width 0.1)
				(type default)
			)
			(layer "F.Fab")
		)
		(fp_line
			(start 0.67945 -0.3048)
			(end 0.67945 0.3048)
			(stroke
				(width 0.1)
				(type default)
			)
			(layer "F.Fab")
		)
		(fp_line
			(start 0.12065 -0.3048)
			(end 0.67945 -0.3048)
			(stroke
				(width 0.1)
				(type default)
			)
			(layer "F.Fab")
		)
		(fp_line
			(start 0.12065 -0.2794)
			(end 0.12065 -0.3048)
			(stroke
				(width 0.1)
				(type default)
			)
			(layer "F.Fab")
		)
		(fp_line
			(start -0.12065 -0.2794)
			(end 0.12065 -0.2794)
			(stroke
				(width 0.1)
				(type default)
			)
			(layer "F.Fab")
		)
		(fp_line
			(start 0.120396 0.2794)
			(end -0.12065 0.2794)
			(stroke
				(width 0.1)
				(type default)
			)
			(layer "F.Fab")
		)
		(fp_line
			(start -0.12065 0.2794)
			(end -0.12065 0.3048)
			(stroke
				(width 0.1)
				(type default)
			)
			(layer "F.Fab")
		)
		(fp_line
			(start 0.67945 0.3048)
			(end 0.120396 0.3048)
			(stroke
				(width 0.1)
				(type default)
			)
			(layer "F.Fab")
		)
		(fp_line
			(start 0.120396 0.3048)
			(end 0.120396 0.2794)
			(stroke
				(width 0.1)
				(type default)
			)
			(layer "F.Fab")
		)
		(fp_line
			(start -0.12065 0.3048)
			(end -0.67945 0.3048)
			(stroke
				(width 0.1)
				(type default)
			)
			(layer "F.Fab")
		)
		(fp_line
			(start -0.67945 0.3048)
			(end -0.67945 -0.305054)
			(stroke
				(width 0.1)
				(type default)
			)
			(layer "F.Fab")
		)
		(pad "1" smd circle
			(at -0.40005 0 90)
			(size 0 0)
			(layers "F.Cu" "F.Mask" "F.Paste")
			(net "P3V3_SSD3_CO_GATE")
		)
		(pad "2" smd circle
			(at 0.40005 0 90)
			(size 0 0)
			(layers "F.Cu" "F.Mask" "F.Paste")
			(net "GND")
		)
	)
	(footprint ""
		(layer "F.Cu")
		(at 213.598506 -66.32194 -90)
		(property "Reference" "PC851"
			(at 0 0 270)
			(layer "F.SilkS")
			(hide yes)
			(effects
				(font
					(size 1.27 1.27)
				)
			)
		)
		(property "Value" ""
			(at 0 0 270)
			(layer "F.Fab")
			(effects
				(font
					(size 1.27 1.27)
				)
			)
		)
		(duplicate_pad_numbers_are_jumpers no)
		(fp_line
			(start -0.7874 0.4064)
			(end -0.7874 -0.4064)
			(stroke
				(width 0.1524)
				(type default)
			)
			(layer "F.SilkS")
		)
		(fp_line
			(start 0.7874 0.4064)
			(end -0.7874 0.4064)
			(stroke
				(width 0.1524)
				(type default)
			)
			(layer "F.SilkS")
		)
		(fp_line
			(start -0.7874 -0.4064)
			(end 0.7874 -0.4064)
			(stroke
				(width 0.1524)
				(type default)
			)
			(layer "F.SilkS")
		)
		(fp_line
			(start 0.7874 -0.4064)
			(end 0.7874 0.4064)
			(stroke
				(width 0.1524)
				(type default)
			)
			(layer "F.SilkS")
		)
		(fp_line
			(start -0.67945 0.3048)
			(end -0.67945 -0.305054)
			(stroke
				(width 0.1)
				(type default)
			)
			(layer "F.Fab")
		)
		(fp_line
			(start -0.12065 0.3048)
			(end -0.67945 0.3048)
			(stroke
				(width 0.1)
				(type default)
			)
			(layer "F.Fab")
		)
		(fp_line
			(start 0.120396 0.3048)
			(end 0.120396 0.2794)
			(stroke
				(width 0.1)
				(type default)
			)
			(layer "F.Fab")
		)
		(fp_line
			(start 0.67945 0.3048)
			(end 0.120396 0.3048)
			(stroke
				(width 0.1)
				(type default)
			)
			(layer "F.Fab")
		)
		(fp_line
			(start -0.12065 0.2794)
			(end -0.12065 0.3048)
			(stroke
				(width 0.1)
				(type default)
			)
			(layer "F.Fab")
		)
		(fp_line
			(start 0.120396 0.2794)
			(end -0.12065 0.2794)
			(stroke
				(width 0.1)
				(type default)
			)
			(layer "F.Fab")
		)
		(fp_line
			(start -0.12065 -0.2794)
			(end 0.12065 -0.2794)
			(stroke
				(width 0.1)
				(type default)
			)
			(layer "F.Fab")
		)
		(fp_line
			(start 0.12065 -0.2794)
			(end 0.12065 -0.3048)
			(stroke
				(width 0.1)
				(type default)
			)
			(layer "F.Fab")
		)
		(fp_line
			(start 0.12065 -0.3048)
			(end 0.67945 -0.3048)
			(stroke
				(width 0.1)
				(type default)
			)
			(layer "F.Fab")
		)
		(fp_line
			(start 0.67945 -0.3048)
			(end 0.67945 0.3048)
			(stroke
				(width 0.1)
				(type default)
			)
			(layer "F.Fab")
		)
		(fp_line
			(start -0.67945 -0.305054)
			(end -0.12065 -0.305054)
			(stroke
				(width 0.1)
				(type default)
			)
			(layer "F.Fab")
		)
		(fp_line
			(start -0.12065 -0.305054)
			(end -0.12065 -0.2794)
			(stroke
				(width 0.1)
				(type default)
			)
			(layer "F.Fab")
		)
		(pad "1" smd circle
			(at -0.40005 0 270)
			(size 0 0)
			(layers "F.Cu" "F.Mask" "F.Paste")
			(net "P12V_SSD7_CO_GATE")
		)
		(pad "2" smd circle
			(at 0.40005 0 270)
			(size 0 0)
			(layers "F.Cu" "F.Mask" "F.Paste")
			(net "GND")
		)
	)
	(footprint ""
		(layer "F.Cu")
		(at 396.947136 -54.3941)
		(property "Reference" "PU41"
			(at -1.670812 3.085592 0)
			(unlocked yes)
			(layer "F.SilkS")
			(effects
				(font
					(size 0.7874 0.5842)
					(thickness 0.1524)
				)
				(justify left)
			)
		)
		(property "Value" ""
			(at 0 0 0)
			(layer "F.Fab")
			(effects
				(font
					(size 1.27 1.27)
				)
			)
		)
		(duplicate_pad_numbers_are_jumpers no)
		(fp_line
			(start -1.943608 -1.549908)
			(end 1.943608 -1.549908)
			(stroke
				(width 0.1524)
				(type default)
			)
			(layer "F.SilkS")
		)
		(fp_line
			(start -1.943608 1.549908)
			(end -1.943608 -1.549908)
			(stroke
				(width 0.1524)
				(type default)
			)
			(layer "F.SilkS")
		)
		(fp_line
			(start 1.943608 -1.549908)
			(end 1.943608 1.549908)
			(stroke
				(width 0.1524)
				(type default)
			)
			(layer "F.SilkS")
		)
		(fp_line
			(start 1.943608 1.549908)
			(end -1.943608 1.549908)
			(stroke
				(width 0.1524)
				(type default)
			)
			(layer "F.SilkS")
		)
		(fp_poly
			(pts
				(xy -2.019808 -1.549908) (xy -1.257808 -1.549908) (xy -1.257808 -1.880108) (xy -2.019808 -1.880108)
			)
			(stroke
				(width 0)
				(type default)
			)
			(fill yes)
			(layer "F.SilkS")
		)
		(fp_line
			(start -1.549908 -1.549908)
			(end 1.549908 -1.549908)
			(stroke
				(width 0.1)
				(type default)
			)
			(layer "F.Fab")
		)
		(fp_line
			(start -1.549908 1.549908)
			(end -1.549908 -1.549908)
			(stroke
				(width 0.1)
				(type default)
			)
			(layer "F.Fab")
		)
		(fp_line
			(start 1.549908 -1.549908)
			(end 1.549908 1.549908)
			(stroke
				(width 0.1)
				(type default)
			)
			(layer "F.Fab")
		)
		(fp_line
			(start 1.549908 1.549908)
			(end -1.549908 1.549908)
			(stroke
				(width 0.1)
				(type default)
			)
			(layer "F.Fab")
		)
		(fp_poly
			(pts
				(xy -2.019808 -1.549908) (xy -1.257808 -1.549908) (xy -1.257808 -1.880108) (xy -2.019808 -1.880108)
			)
			(stroke
				(width 0)
				(type default)
			)
			(fill yes)
			(layer "F.Fab")
		)
		(pad "1" smd rect
			(at -1.500124 -1.249934 270)
			(size 0.2794 0.6096)
			(layers "F.Cu" "F.Mask" "F.Paste")
			(net "P12V_SSD13_R")
		)
		(pad "2" smd rect
			(at -1.500124 -0.750062 270)
			(size 0.2794 0.6096)
			(layers "F.Cu" "F.Mask" "F.Paste")
			(net "P12V_SSD13_R")
		)
		(pad "3" smd rect
			(at -1.500124 -0.249936 270)
			(size 0.2794 0.6096)
			(layers "F.Cu" "F.Mask" "F.Paste")
			(net "P12V_SSD13_R")
		)
		(pad "4" smd rect
			(at -1.500124 0.249936 270)
			(size 0.2794 0.6096)
			(layers "F.Cu" "F.Mask" "F.Paste")
			(net "P12V_SSD13_R")
		)
		(pad "5" smd rect
			(at -1.500124 0.750062 270)
			(size 0.2794 0.6096)
			(layers "F.Cu" "F.Mask" "F.Paste")
			(net "P12V_SSD13_R")
		)
		(pad "6" smd rect
			(at -1.500124 1.249934 270)
			(size 0.2794 0.6096)
			(layers "F.Cu" "F.Mask" "F.Paste")
			(net "GND")
		)
		(pad "7" smd rect
			(at 1.500124 1.249934 270)
			(size 0.2794 0.6096)
			(layers "F.Cu" "F.Mask" "F.Paste")
			(net "P12V_SSD13_SS")
		)
		(pad "8" smd rect
			(at 1.500124 0.750062 270)
			(size 0.2794 0.6096)
			(layers "F.Cu" "F.Mask" "F.Paste")
			(net "PWRGD_P12V_SSD13")
		)
		(pad "9" smd rect
			(at 1.500124 0.249936 270)
			(size 0.2794 0.6096)
			(layers "F.Cu" "F.Mask" "F.Paste")
			(net "P12V_SSD13_OCP")
		)
		(pad "10" smd rect
			(at 1.500124 -0.249936 270)
			(size 0.2794 0.6096)
			(layers "F.Cu" "F.Mask" "F.Paste")
			(net "P5V_AUX")
		)
		(pad "11" smd rect
			(at 1.500124 -0.750062 270)
			(size 0.2794 0.6096)
			(layers "F.Cu" "F.Mask" "F.Paste")
			(net "SSD13_PWR_EN_R")
		)
		(pad "12" smd rect
			(at 1.500124 -1.249934 270)
			(size 0.2794 0.6096)
			(layers "F.Cu" "F.Mask" "F.Paste")
			(net "P12V_AUX")
		)
		(pad "13" smd rect
			(at 0 0)
			(size 1.9812 2.7178)
			(layers "F.Cu" "F.Mask" "F.Paste")
			(net "P12V_AUX")
		)
		(zone
			(layer "F.Cu")
			(hatch none 0.5)
			(connect_pads
				(clearance 0)
			)
			(min_thickness 0.25)
			(keepout
				(tracks not_allowed)
				(vias allowed)
				(pads allowed)
				(copperpour not_allowed)
				(footprints allowed)
			)
			(placement
				(enabled no)
				(sheetname "")
			)
			(fill
				(thermal_gap 0.5)
				(thermal_bridge_width 0.5)
				(island_removal_mode 0)
			)
			(polygon
				(pts
					(xy 398.090136 -55.9435) (xy 398.090136 -55.8165) (xy 398.090136 -52.8447) (xy 398.090136 -52.844192)
					(xy 395.804136 -52.844192) (xy 395.804136 -52.8447) (xy 395.804136 -52.9717) (xy 395.804136 -54.3941)
					(xy 395.905736 -54.3941) (xy 395.905736 -52.9717) (xy 397.988536 -52.9717) (xy 397.988536 -55.8165)
					(xy 395.905736 -55.8165) (xy 395.905736 -54.4195) (xy 395.804136 -54.4195) (xy 395.804136 -55.8165)
					(xy 395.804136 -55.9435) (xy 395.804136 -55.944008) (xy 398.090136 -55.944008)
				)
			)
		)
	)
)
